# BASEBOARD_FAB2 (Tioga Pass) — schematic netlist excerpt (pin names and nets, part order shuffled) for the footprints in the layout excerpt that follows; sources: Cadence DE-HDL packaged netlist, KiCad conversion of Wiwynn_Tioga_Pass_MB.brd

R1W9  RES  22.1 1.0% CHIP  pkg 0402  page 239 : A = PWRGD_P2V5_BMC_STBY_R ; B = PWRGD_P2V5_BMC_STBY
R12W20  665KR2B-GP  0.1%  pkg SMD-RG2  page 197 : \1\ = VR_PVDDQ_KLM_AIINSEN ; \2\ = VR_PVDDQ_KLM_VINSEN
C1E14  CAP_A  0.1UF 16V 10% X7R  pkg 0402V  page 207 : A = VR_FET_SW_P12V_STBY_PVCCIN_CPU1 ; B = GND

(kicad_pcb
	(version 20260206)
	(generator "pcbnew")
	(generator_version "10.0")
	(general
		(thickness 1.6)
		(legacy_teardrops no)
	)
	(paper "A4")
	(title_block
		(title "Wiwynn_Tioga_Pass_MB.brd")
		(comment 1 "Tioga Pass / footprints 1139-1141 of 4770")
	)
	(layers
		(0 "F.Cu" signal "TOP")
		(4 "In1.Cu" signal "L2GND")
		(6 "In2.Cu" signal "L3")
		(8 "In3.Cu" signal "L4GND")
		(10 "In4.Cu" signal "L5")
		(12 "In5.Cu" signal "L6GND")
		(14 "In6.Cu" signal "L7VCC")
		(16 "In7.Cu" signal "L8VCC")
		(18 "In8.Cu" signal "L9GND")
		(20 "In9.Cu" signal "L10")
		(22 "In10.Cu" signal "L11GND")
		(24 "In11.Cu" signal "L12")
		(26 "In12.Cu" signal "L13GND")
		(2 "B.Cu" signal "BOTTOM")
		(9 "F.Adhes" user "F.Adhesive")
		(11 "B.Adhes" user "B.Adhesive")
		(13 "F.Paste" user "Package Geometry/Pastemask Top")
		(15 "B.Paste" user "Package Geometry/Pastemask Bottom")
		(5 "F.SilkS" user "Ref Des/Silkscreen Top")
		(7 "B.SilkS" user "Ref Des/Silkscreen Bottom")
		(1 "F.Mask" user "Board Geometry/Soldermask Top")
		(3 "B.Mask" user "Board Geometry/Soldermask Bottom")
		(17 "Dwgs.User" user "User.Drawings")
		(19 "Cmts.User" user "User.Comments")
		(21 "Eco1.User" user "User.Eco1")
		(23 "Eco2.User" user "User.Eco2")
		(25 "Edge.Cuts" user "Board Geometry/Outline")
		(27 "Margin" user)
		(31 "F.CrtYd" user "Package Geometry/Place Bound Top")
		(29 "B.CrtYd" user "Package Geometry/Place Bound Bottom")
		(35 "F.Fab" user "Ref Des/Assembly Top")
		(33 "B.Fab" user "Ref Des/Assembly Bottom")
	)
	(footprint ""
		(layer "F.Cu")
		(at 33.243012 -60.376308 90)
		(property "Reference" "C1E14"
			(at 0 0 90)
			(layer "F.SilkS")
			(hide yes)
			(effects
				(font
					(size 1.27 1.27)
				)
			)
		)
		(property "Value" ""
			(at 0 0 90)
			(layer "F.Fab")
			(effects
				(font
					(size 1.27 1.27)
				)
			)
		)
		(duplicate_pad_numbers_are_jumpers no)
		(fp_rect
			(start 0.3048 0.9906)
			(end -0.3048 -0.1016)
			(stroke
				(width 0)
				(type default)
			)
			(fill no)
			(layer "F.CrtYd")
		)
		(fp_line
			(start 0.3048 -0.1016)
			(end -0.3048 -0.1016)
			(stroke
				(width 0.1)
				(type default)
			)
			(layer "F.Fab")
		)
		(fp_line
			(start -0.3048 -0.1016)
			(end -0.3048 0.9906)
			(stroke
				(width 0.1)
				(type default)
			)
			(layer "F.Fab")
		)
		(fp_line
			(start 0.3048 0.9906)
			(end 0.3048 -0.1016)
			(stroke
				(width 0.1)
				(type default)
			)
			(layer "F.Fab")
		)
		(fp_line
			(start -0.3048 0.9906)
			(end 0.3048 0.9906)
			(stroke
				(width 0.1)
				(type default)
			)
			(layer "F.Fab")
		)
		(pad "1" smd rect
			(at 0 0 90)
			(size 0.508 0.508)
			(layers "F.Cu" "F.Mask" "F.Paste")
			(net "VR_FET_SW_P12V_STBY_PVCCIN_CPU1")
		)
		(pad "2" smd rect
			(at 0 0.889 90)
			(size 0.508 0.508)
			(layers "F.Cu" "F.Mask" "F.Paste")
			(net "GND")
		)
		(zone
			(layer "F.Cu")
			(hatch none 0.5)
			(connect_pads
				(clearance 0)
			)
			(min_thickness 0.25)
			(keepout
				(tracks not_allowed)
				(vias allowed)
				(pads allowed)
				(copperpour not_allowed)
				(footprints allowed)
			)
			(placement
				(enabled no)
				(sheetname "")
			)
			(fill
				(thermal_gap 0.5)
				(thermal_bridge_width 0.5)
				(island_removal_mode 0)
			)
			(polygon
				(pts
					(xy 33.878012 -60.630308) (xy 33.497012 -60.630308) (xy 33.497012 -60.122308) (xy 33.878012 -60.122308)
				)
			)
		)
		(zone
			(layer "F.Cu")
			(hatch none 0.5)
			(connect_pads
				(clearance 0)
			)
			(min_thickness 0.25)
			(keepout
				(tracks allowed)
				(vias not_allowed)
				(pads allowed)
				(copperpour not_allowed)
				(footprints allowed)
			)
			(placement
				(enabled no)
				(sheetname "")
			)
			(fill
				(thermal_gap 0.5)
				(thermal_bridge_width 0.5)
				(island_removal_mode 0)
			)
			(polygon
				(pts
					(xy 33.878012 -60.630308) (xy 33.497012 -60.630308) (xy 33.497012 -60.122308) (xy 33.878012 -60.122308)
				)
			)
		)
	)
	(footprint ""
		(layer "F.Cu")
		(at 447.548 -20.2565)
		(property "Reference" "R1W9"
			(at -0.8382 -0.67818 0)
			(unlocked yes)
			(layer "F.SilkS")
			(effects
				(font
					(size 0.4064 0.254)
					(thickness 0.1524)
				)
				(justify left)
			)
		)
		(property "Value" ""
			(at 0 0 0)
			(layer "F.Fab")
			(effects
				(font
					(size 1.27 1.27)
				)
			)
		)
		(duplicate_pad_numbers_are_jumpers no)
		(fp_poly
			(pts
				(xy -0.2794 -0.1016) (xy 0.2794 -0.1016) (xy 0.2794 0.9906) (xy -0.2794 0.9906)
			)
			(stroke
				(width 0)
				(type default)
			)
			(fill no)
			(layer "F.CrtYd")
		)
		(fp_line
			(start -0.2794 -0.1016)
			(end -0.2794 0.9906)
			(stroke
				(width 0.1)
				(type default)
			)
			(layer "F.Fab")
		)
		(fp_line
			(start -0.2794 0.9906)
			(end 0.2794 0.9906)
			(stroke
				(width 0.1)
				(type default)
			)
			(layer "F.Fab")
		)
		(fp_line
			(start 0.2794 -0.1016)
			(end -0.2794 -0.1016)
			(stroke
				(width 0.1)
				(type default)
			)
			(layer "F.Fab")
		)
		(fp_line
			(start 0.2794 0.9906)
			(end 0.2794 -0.1016)
			(stroke
				(width 0.1)
				(type default)
			)
			(layer "F.Fab")
		)
		(pad "1" smd rect
			(at 0 0)
			(size 0.508 0.508)
			(layers "F.Cu" "F.Mask" "F.Paste")
			(net "PWRGD_P2V5_BMC_STBY_R")
		)
		(pad "2" smd rect
			(at 0 0.889)
			(size 0.508 0.508)
			(layers "F.Cu" "F.Mask" "F.Paste")
			(net "PWRGD_P2V5_BMC_STBY")
		)
		(zone
			(layer "F.Cu")
			(hatch none 0.5)
			(connect_pads
				(clearance 0)
			)
			(min_thickness 0.25)
			(keepout
				(tracks allowed)
				(vias not_allowed)
				(pads allowed)
				(copperpour not_allowed)
				(footprints allowed)
			)
			(placement
				(enabled no)
				(sheetname "")
			)
			(fill
				(thermal_gap 0.5)
				(thermal_bridge_width 0.5)
				(island_removal_mode 0)
			)
			(polygon
				(pts
					(xy 447.294 -20.0025) (xy 447.802 -20.0025) (xy 447.802 -19.6215) (xy 447.294 -19.6215)
				)
			)
		)
		(zone
			(layer "F.Cu")
			(hatch none 0.5)
			(connect_pads
				(clearance 0)
			)
			(min_thickness 0.25)
			(keepout
				(tracks not_allowed)
				(vias allowed)
				(pads allowed)
				(copperpour not_allowed)
				(footprints allowed)
			)
			(placement
				(enabled no)
				(sheetname "")
			)
			(fill
				(thermal_gap 0.5)
				(thermal_bridge_width 0.5)
				(island_removal_mode 0)
			)
			(polygon
				(pts
					(xy 447.294 -19.6215) (xy 447.802 -19.6215) (xy 447.802 -20.0025) (xy 447.294 -20.0025)
				)
			)
		)
	)
	(footprint ""
		(layer "F.Cu")
		(at 7.33298 -128.36779)
		(property "Reference" "R12W20"
			(at 0 0 0)
			(layer "F.SilkS")
			(hide yes)
			(effects
				(font
					(size 1.27 1.27)
				)
			)
		)
		(property "Value" "*"
			(at 0.064008 -4.108196 0)
			(unlocked yes)
			(layer "F.Fab")
			(hide yes)
			(effects
				(font
					(size 1.27 1.016)
					(thickness 0.1524)
				)
			)
		)
		(property "Device Type" "665KR2B-GP_SMD-RG2-665KR2B-GP,A"
			(at 0.064008 -5.632196 0)
			(unlocked yes)
			(layer "F.Fab")
			(hide yes)
			(effects
				(font
					(size 1.27 1.016)
					(thickness 0.1524)
				)
			)
		)
		(duplicate_pad_numbers_are_jumpers no)
		(fp_line
			(start -0.508 -0.9398)
			(end -0.508 0.9398)
			(stroke
				(width 0.1524)
				(type default)
			)
			(layer "F.SilkS")
		)
		(fp_line
			(start 0.508 -0.9398)
			(end -0.508 -0.9398)
			(stroke
				(width 0.1524)
				(type default)
			)
			(layer "F.SilkS")
		)
		(fp_rect
			(start -0.508 0.9398)
			(end 0.508 -0.9398)
			(stroke
				(width 0)
				(type default)
			)
			(fill no)
			(layer "F.CrtYd")
		)
		(fp_rect
			(start -0.508 0.9398)
			(end 0.508 -0.9398)
			(stroke
				(width 0)
				(type default)
			)
			(fill no)
			(layer "F.Fab")
		)
		(pad "1" smd custom
			(at 0 -0.4445)
			(size 0.1397 0.1397)
			(layers "F.Cu" "F.Mask" "F.Paste")
			(net "VR_PVDDQ_KLM_AIINSEN")
			(options
				(clearance outline)
				(anchor circle)
			)
			(primitives
				(gr_poly
					(pts
						(arc
							(start -0.1778 -0.2794)
							(mid -0.249642 -0.249642)
							(end -0.2794 -0.1778)
						)
						(arc
							(start -0.2794 0.1778)
							(mid -0.249642 0.249642)
							(end -0.1778 0.2794)
						)
						(arc
							(start 0.1778 0.2794)
							(mid 0.249642 0.249642)
							(end 0.2794 0.1778)
						)
						(arc
							(start 0.2794 -0.1778)
							(mid 0.249642 -0.249642)
							(end 0.1778 -0.2794)
						)
					)
					(width 0)
					(fill yes)
				)
			)
		)
		(pad "2" smd custom
			(at 0 0.4445)
			(size 0.1397 0.1397)
			(layers "F.Cu" "F.Mask" "F.Paste")
			(net "VR_PVDDQ_KLM_VINSEN")
			(options
				(clearance outline)
				(anchor circle)
			)
			(primitives
				(gr_poly
					(pts
						(arc
							(start -0.1778 -0.2794)
							(mid -0.249642 -0.249642)
							(end -0.2794 -0.1778)
						)
						(arc
							(start -0.2794 0.1778)
							(mid -0.249642 0.249642)
							(end -0.1778 0.2794)
						)
						(arc
							(start 0.1778 0.2794)
							(mid 0.249642 0.249642)
							(end 0.2794 0.1778)
						)
						(arc
							(start 0.2794 -0.1778)
							(mid 0.249642 -0.249642)
							(end 0.1778 -0.2794)
						)
					)
					(width 0)
					(fill yes)
				)
			)
		)
	)
)
